(kicad_pcb
	(version 20241229)
	(generator "pcbnew")
	(generator_version "9.0")
	(general
		(thickness 1.711)
		(legacy_teardrops no)
	)
	(paper "A4")
	(title_block
		(title "Antmicro Baseboard for Jetson AGX Thor")
		(date "2026-02-18")
		(rev "1.1.0")
		(company "Antmicro Ltd")
		(comment 1 "www.antmicro.com")
		(comment 9 "footprints 395-398 of 1170")
	)
	(layers
		(0 "F.Cu" signal)
		(4 "In1.Cu" signal)
		(6 "In2.Cu" signal)
		(8 "In3.Cu" signal)
		(10 "In4.Cu" jumper)
		(12 "In5.Cu" signal)
		(14 "In6.Cu" signal)
		(16 "In7.Cu" signal)
		(18 "In8.Cu" signal)
		(2 "B.Cu" signal)
		(9 "F.Adhes" user "F.Adhesive")
		(11 "B.Adhes" user "B.Adhesive")
		(13 "F.Paste" user)
		(15 "B.Paste" user)
		(5 "F.SilkS" user "F.Silkscreen")
		(7 "B.SilkS" user "B.Silkscreen")
		(1 "F.Mask" user)
		(3 "B.Mask" user)
		(17 "Dwgs.User" user "User.Drawings")
		(19 "Cmts.User" user "User.Comments")
		(21 "Eco1.User" user "User.Eco1")
		(23 "Eco2.User" user "User.Eco2")
		(25 "Edge.Cuts" user)
		(27 "Margin" user)
		(31 "F.CrtYd" user "F.Courtyard")
		(29 "B.CrtYd" user "B.Courtyard")
		(35 "F.Fab" user)
		(33 "B.Fab" user)
	)
	(footprint "antmicro-footprints:SOT-523"
		(layer "F.Cu")
		(at 83.51 59.75 -90)
		(property "Reference" "Q17"
			(at 1.25 -1.69 180)
			(layer "F.SilkS")
			(effects
				(font
					(size 0.7 0.7)
					(thickness 0.15)
				)
				(justify right top)
			)
		)
		(property "Value" "DMG1012T-7"
			(at 0.1 1.824 90)
			(layer "F.Fab")
			(effects
				(font
					(size 0.7 0.7)
					(thickness 0.15)
				)
				(justify right top)
			)
		)
		(property "Datasheet" "https://www.diodes.com/assets/Datasheets/ds31783.pdf"
			(at 0 0 90)
			(layer "F.Fab")
			(hide yes)
			(effects
				(font
					(size 1.27 1.27)
					(thickness 0.15)
				)
			)
		)
		(property "Description" "Power MOSFET, N Channel, 20 V, 630 mA, 0.3 ohm, SOT-523, Surface Mount"
			(at 0 0 90)
			(layer "F.Fab")
			(hide yes)
			(effects
				(font
					(size 1.27 1.27)
					(thickness 0.15)
				)
			)
		)
		(property "MPN" "DMG1012T-7"
			(at 0 0 270)
			(unlocked yes)
			(layer "F.Fab")
			(hide yes)
			(effects
				(font
					(size 1 1)
					(thickness 0.15)
				)
			)
		)
		(property "Manufacturer" "Diodes Incorporated"
			(at 0 0 270)
			(unlocked yes)
			(layer "F.Fab")
			(hide yes)
			(effects
				(font
					(size 1 1)
					(thickness 0.15)
				)
			)
		)
		(property "Author" "Antmicro"
			(at 0 0 270)
			(unlocked yes)
			(layer "F.Fab")
			(hide yes)
			(effects
				(font
					(size 1 1)
					(thickness 0.15)
				)
			)
		)
		(property "License" "Apache-2.0"
			(at 0 0 270)
			(unlocked yes)
			(layer "F.Fab")
			(hide yes)
			(effects
				(font
					(size 1 1)
					(thickness 0.15)
				)
			)
		)
		(sheetname "/SoM_Power/")
		(sheetfile "som_power.kicad_sch")
		(attr smd)
		(fp_line
			(start -0.927 -0.051)
			(end -0.927 -0.351)
			(stroke
				(width 0.15)
				(type solid)
			)
			(layer "F.SilkS")
		)
		(fp_line
			(start -0.927 -0.351)
			(end -0.725 -0.551)
			(stroke
				(width 0.15)
				(type solid)
			)
			(layer "F.SilkS")
		)
		(fp_line
			(start -0.725 -0.551)
			(end -0.277 -0.551)
			(stroke
				(width 0.15)
				(type solid)
			)
			(layer "F.SilkS")
		)
		(fp_line
			(start -0.277 -0.551)
			(end -0.277 -0.75)
			(stroke
				(width 0.15)
				(type solid)
			)
			(layer "F.SilkS")
		)
		(fp_circle
			(center -0.9652 0.9652)
			(end -0.9152 0.9652)
			(stroke
				(width 0.15)
				(type solid)
			)
			(fill yes)
			(layer "F.SilkS")
		)
		(fp_line
			(start -1.12 1.15)
			(end 1.1 1.15)
			(stroke
				(width 0.05)
				(type solid)
			)
			(layer "F.CrtYd")
		)
		(fp_line
			(start -1.12 -1.16)
			(end -1.12 1.15)
			(stroke
				(width 0.05)
				(type solid)
			)
			(layer "F.CrtYd")
		)
		(fp_line
			(start -1.12 -1.16)
			(end 1.1 -1.16)
			(stroke
				(width 0.05)
				(type solid)
			)
			(layer "F.CrtYd")
		)
		(fp_line
			(start 1.1 -1.16)
			(end 1.1 1.15)
			(stroke
				(width 0.05)
				(type solid)
			)
			(layer "F.CrtYd")
		)
		(fp_line
			(start 0.8 0.424)
			(end -0.802 0.424)
			(stroke
				(width 0.15)
				(type solid)
			)
			(layer "F.Fab")
		)
		(fp_line
			(start -0.802 -0.276)
			(end -0.802 0.424)
			(stroke
				(width 0.15)
				(type solid)
			)
			(layer "F.Fab")
		)
		(fp_line
			(start -0.652 -0.425)
			(end -0.802 -0.276)
			(stroke
				(width 0.15)
				(type solid)
			)
			(layer "F.Fab")
		)
		(fp_line
			(start 0.8 -0.425)
			(end 0.8 0.424)
			(stroke
				(width 0.15)
				(type solid)
			)
			(layer "F.Fab")
		)
		(fp_line
			(start 0.8 -0.425)
			(end -0.652 -0.425)
			(stroke
				(width 0.15)
				(type solid)
			)
			(layer "F.Fab")
		)
		(fp_circle
			(center -0.9652 0.9652)
			(end -0.9144 0.9652)
			(stroke
				(width 0.15)
				(type solid)
			)
			(fill no)
			(layer "F.Fab")
		)
		(fp_text user "${REFERENCE}"
			(at -1.12 3.824 90)
			(layer "F.Fab")
			(effects
				(font
					(size 0.7 0.7)
					(thickness 0.15)
				)
				(justify right top)
			)
		)
		(fp_text user "License: Apache-2.0"
			(at -1.12 5.024 90)
			(layer "F.Fab")
			(effects
				(font
					(size 0.7 0.7)
					(thickness 0.15)
				)
				(justify right top)
			)
		)
		(fp_text user "Author: Antmicro"
			(at -1.12 6.224 90)
			(layer "F.Fab")
			(effects
				(font
					(size 0.7 0.7)
					(thickness 0.15)
				)
				(justify right top)
			)
		)
		(pad "1" smd rect
			(at -0.5 0.65 270)
			(size 0.4 0.51)
			(layers "F.Cu" "F.Mask" "F.Paste")
			(net 11 "+1V8")
			(pinfunction "G")
			(pintype "input")
		)
		(pad "2" smd rect
			(at 0.498 0.65 270)
			(size 0.4 0.51)
			(layers "F.Cu" "F.Mask" "F.Paste")
			(net 605 "/SoM_Power/~{MODULE_SHDN}")
			(pinfunction "S")
			(pintype "passive")
		)
		(pad "3" smd rect
			(at 0 -0.652 270)
			(size 0.4 0.51)
			(layers "F.Cu" "F.Mask" "F.Paste")
			(net 887 "Net-(Q17-D)")
			(pinfunction "D")
			(pintype "passive")
		)
	)
	(footprint "antmicro-footprints:SOT-23-8"
		(layer "F.Cu")
		(at 161.322234 81.952234 -90)
		(descr "http://www.ti.com/lit/ds/symlink/ina219.pdf")
		(property "Reference" "U66"
			(at -1.65 2.76 90)
			(layer "F.SilkS")
			(effects
				(font
					(size 0.7 0.7)
					(thickness 0.15)
				)
				(justify right top)
			)
		)
		(property "Value" "INA219AIDCNR"
			(at -2.925 2.8 90)
			(layer "F.Fab")
			(effects
				(font
					(size 0.7 0.7)
					(thickness 0.15)
				)
				(justify right top)
			)
		)
		(property "Datasheet" "https://www.ti.com/lit/ds/symlink/ina219.pdf?ts=1713856455637&ref_url=https%253A%252F%252Fwww.mouser.es%252F"
			(at 0 0 90)
			(layer "F.Fab")
			(hide yes)
			(effects
				(font
					(size 1.27 1.27)
					(thickness 0.15)
				)
			)
		)
		(property "Description" "Zerø-Drift, Bidirectional Current/Power Monitor With I2C Interface"
			(at 0 0 90)
			(layer "F.Fab")
			(hide yes)
			(effects
				(font
					(size 1.27 1.27)
					(thickness 0.15)
				)
			)
		)
		(property "Manufacturer" "Texas Instruments"
			(at 0 0 270)
			(unlocked yes)
			(layer "F.Fab")
			(hide yes)
			(effects
				(font
					(size 1 1)
					(thickness 0.15)
				)
			)
		)
		(property "MPN" "INA219AIDCNR"
			(at 0 0 270)
			(unlocked yes)
			(layer "F.Fab")
			(hide yes)
			(effects
				(font
					(size 1 1)
					(thickness 0.15)
				)
			)
		)
		(property "Author" "Antmicro"
			(at 0 0 270)
			(unlocked yes)
			(layer "F.Fab")
			(hide yes)
			(effects
				(font
					(size 1 1)
					(thickness 0.15)
				)
			)
		)
		(property "License" "Apache-2.0"
			(at 0 0 270)
			(unlocked yes)
			(layer "F.Fab")
			(hide yes)
			(effects
				(font
					(size 1 1)
					(thickness 0.15)
				)
			)
		)
		(component_classes
			(class "DCDC_20V")
		)
		(sheetname "/DCDC/")
		(sheetfile "dcdc.kicad_sch")
		(attr smd)
		(fp_line
			(start -0.987 1.6)
			(end -0.987 1.324)
			(stroke
				(width 0.15)
				(type solid)
			)
			(layer "F.SilkS")
		)
		(fp_line
			(start -0.613 1.6)
			(end -0.987 1.6)
			(stroke
				(width 0.15)
				(type solid)
			)
			(layer "F.SilkS")
		)
		(fp_line
			(start 1 1.6)
			(end 0.6 1.6)
			(stroke
				(width 0.15)
				(type solid)
			)
			(layer "F.SilkS")
		)
		(fp_line
			(start 1 1.3)
			(end 1 1.6)
			(stroke
				(width 0.15)
				(type solid)
			)
			(layer "F.SilkS")
		)
		(fp_line
			(start -1 -1.3)
			(end -1 -1.6)
			(stroke
				(width 0.15)
				(type solid)
			)
			(layer "F.SilkS")
		)
		(fp_line
			(start 1 -1.3)
			(end 1 -1.6)
			(stroke
				(width 0.15)
				(type solid)
			)
			(layer "F.SilkS")
		)
		(fp_line
			(start -1 -1.6)
			(end -0.6 -1.6)
			(stroke
				(width 0.15)
				(type solid)
			)
			(layer "F.SilkS")
		)
		(fp_line
			(start 1 -1.6)
			(end 0.625 -1.6)
			(stroke
				(width 0.15)
				(type solid)
			)
			(layer "F.SilkS")
		)
		(fp_circle
			(center -1.3 -1.4)
			(end -1.25 -1.4)
			(stroke
				(width 0.15)
				(type solid)
			)
			(fill yes)
			(layer "F.SilkS")
		)
		(fp_rect
			(start -1.9 -1.75)
			(end 1.898 1.75)
			(stroke
				(width 0.05)
				(type solid)
			)
			(fill no)
			(layer "F.CrtYd")
		)
		(fp_line
			(start -1.4 -1.25)
			(end -1.2 -1.45)
			(stroke
				(width 0.15)
				(type solid)
			)
			(layer "F.Fab")
		)
		(fp_rect
			(start -1.401 -1.45)
			(end 1.398 1.449)
			(stroke
				(width 0.15)
				(type solid)
			)
			(fill no)
			(layer "F.Fab")
		)
		(fp_text user "Author: Antmicro"
			(at -2.925 7.2 90)
			(layer "F.Fab")
			(effects
				(font
					(size 0.7 0.7)
					(thickness 0.15)
				)
				(justify right top)
			)
		)
		(fp_text user "${REFERENCE}"
			(at -2.925 4.8 90)
			(layer "F.Fab")
			(effects
				(font
					(size 0.7 0.7)
					(thickness 0.15)
				)
				(justify right top)
			)
		)
		(fp_text user "License: Apache-2.0"
			(at -2.925 6 90)
			(layer "F.Fab")
			(effects
				(font
					(size 0.7 0.7)
					(thickness 0.15)
				)
				(justify right top)
			)
		)
		(pad "1" smd roundrect
			(at -1.3 -0.975 180)
			(size 0.45 1.1)
			(layers "F.Cu" "F.Mask" "F.Paste")
			(roundrect_rratio 0.25)
			(net 1284 "Net-(U66-IN+)")
			(pinfunction "IN+")
			(pintype "passive")
		)
		(pad "2" smd roundrect
			(at -1.3 -0.325 180)
			(size 0.45 1.1)
			(layers "F.Cu" "F.Mask" "F.Paste")
			(roundrect_rratio 0.25)
			(net 1221 "Net-(U66-IN-)")
			(pinfunction "IN-")
			(pintype "passive")
		)
		(pad "3" smd roundrect
			(at -1.3 0.325 180)
			(size 0.45 1.1)
			(layers "F.Cu" "F.Mask" "F.Paste")
			(roundrect_rratio 0.25)
			(net 1 "GND")
			(pinfunction "GND")
			(pintype "power_in")
		)
		(pad "4" smd roundrect
			(at -1.3 0.975 180)
			(size 0.45 1.1)
			(layers "F.Cu" "F.Mask" "F.Paste")
			(roundrect_rratio 0.25)
			(net 4 "+3V3_AON")
			(pinfunction "V_{S}")
			(pintype "power_in")
		)
		(pad "5" smd roundrect
			(at 1.3 0.975 180)
			(size 0.45 1.1)
			(layers "F.Cu" "F.Mask" "F.Paste")
			(roundrect_rratio 0.25)
			(net 853 "/I2C_{SYS}.SCL")
			(pinfunction "SCL")
			(pintype "open_collector")
		)
		(pad "6" smd roundrect
			(at 1.3 0.325 180)
			(size 0.45 1.1)
			(layers "F.Cu" "F.Mask" "F.Paste")
			(roundrect_rratio 0.25)
			(net 850 "/I2C_{SYS}.SDA")
			(pinfunction "SDA")
			(pintype "open_collector")
		)
		(pad "7" smd roundrect
			(at 1.3 -0.325 180)
			(size 0.45 1.1)
			(layers "F.Cu" "F.Mask" "F.Paste")
			(roundrect_rratio 0.25)
			(net 853 "/I2C_{SYS}.SCL")
			(pinfunction "A0")
			(pintype "passive")
		)
		(pad "8" smd roundrect
			(at 1.3 -0.975 180)
			(size 0.45 1.1)
			(layers "F.Cu" "F.Mask" "F.Paste")
			(roundrect_rratio 0.25)
			(net 1 "GND")
			(pinfunction "A1")
			(pintype "passive")
		)
	)
	(footprint "antmicro-footprints:Spacer_Drill4.45mm_H4mm_9774040960R"
		(locked yes)
		(layer "F.Cu")
		(at 76.930532 57.71 90)
		(property "Reference" "H6"
			(at -0.89 4.969468 90)
			(layer "F.SilkS")
			(effects
				(font
					(size 0.7 0.7)
					(thickness 0.15)
				)
				(justify left bottom)
			)
		)
		(property "Value" "Spacer_Drill4.45mm_H4mm_9774040960R"
			(at -3.95 5.05 90)
			(layer "F.Fab")
			(effects
				(font
					(size 0.7 0.7)
					(thickness 0.15)
				)
				(justify left bottom)
			)
		)
		(property "Datasheet" "https://www.we-online.com/components/products/datasheet/9774040960R.pdf"
			(at 0 0 90)
			(layer "F.Fab")
			(effects
				(font
					(size 0.7 0.7)
					(thickness 0.15)
				)
				(justify left bottom)
			)
		)
		(property "Description" "Spacer, SMT, Non Stop, Steel, Swage Round, 6 mm x 4 mm, 3.3 mm Internal, WA-SMST Series"
			(at 0 0 90)
			(layer "F.Fab")
			(effects
				(font
					(size 0.7 0.7)
					(thickness 0.15)
				)
				(justify left bottom)
			)
		)
		(property "Manufacturer" "Würth Elektronik"
			(at 0 0 90)
			(unlocked yes)
			(layer "F.Fab")
			(hide yes)
			(effects
				(font
					(size 1 1)
					(thickness 0.15)
				)
			)
		)
		(property "MPN" "9774040960R"
			(at 0 0 90)
			(unlocked yes)
			(layer "F.Fab")
			(hide yes)
			(effects
				(font
					(size 1 1)
					(thickness 0.15)
				)
			)
		)
		(property "Author" "Antmicro"
			(at 0 0 90)
			(unlocked yes)
			(layer "F.Fab")
			(hide yes)
			(effects
				(font
					(size 1 1)
					(thickness 0.15)
				)
			)
		)
		(property "License" "Apache-2.0"
			(at 0 0 90)
			(unlocked yes)
			(layer "F.Fab")
			(hide yes)
			(effects
				(font
					(size 1 1)
					(thickness 0.15)
				)
			)
		)
		(sheetname "/SoM_Power/")
		(sheetfile "som_power.kicad_sch")
		(attr smd)
		(fp_rect
			(start -3.95 -3.95)
			(end 3.95 3.95)
			(stroke
				(width 0.05)
				(type solid)
			)
			(fill no)
			(layer "F.CrtYd")
		)
		(fp_circle
			(center 0 0)
			(end 3.25 0)
			(stroke
				(width 0.05)
				(type solid)
			)
			(fill no)
			(layer "F.CrtYd")
		)
		(fp_circle
			(center 0 0)
			(end 2.564 0)
			(stroke
				(width 0.15)
				(type solid)
			)
			(fill no)
			(layer "F.Fab")
		)
		(fp_text user "${REFERENCE}"
			(at -3.95 7.45 90)
			(layer "F.Fab")
			(effects
				(font
					(size 0.7 0.7)
					(thickness 0.15)
				)
				(justify left bottom)
			)
		)
		(fp_text user "Author: Antmicro"
			(at -3.95 8.65 90)
			(layer "F.Fab")
			(effects
				(font
					(size 0.7 0.7)
					(thickness 0.15)
				)
				(justify left bottom)
			)
		)
		(fp_text user "License: Apache-2.0"
			(at -3.95 6.25 90)
			(layer "F.Fab")
			(effects
				(font
					(size 0.7 0.7)
					(thickness 0.15)
				)
				(justify left bottom)
			)
		)
		(pad "" smd custom
			(at -2.55 -0.55 212.5)
			(size 0.1 0.1)
			(layers "F.Paste")
			(options
				(clearance outline)
				(anchor circle)
			)
			(primitives
				(gr_arc
					(start 0 0)
					(mid 0.704278 1.28373)
					(end 0.608513 2.744826)
					(width 0.7)
				)
			)
		)
		(pad "" smd custom
			(at -0.55 2.55 302.5)
			(size 0.1 0.1)
			(layers "F.Paste")
			(options
				(clearance outline)
				(anchor circle)
			)
			(primitives
				(gr_arc
					(start 0 0)
					(mid 0.704278 1.28373)
					(end 0.608513 2.744826)
					(width 0.7)
				)
			)
		)
		(pad "" smd custom
			(at 0.55 -2.55 122.5)
			(size 0.1 0.1)
			(layers "F.Paste")
			(options
				(clearance outline)
				(anchor circle)
			)
			(primitives
				(gr_arc
					(start 0 0)
					(mid 0.704278 1.28373)
					(end 0.608513 2.744826)
					(width 0.7)
				)
			)
		)
		(pad "" smd custom
			(at 2.55 0.55 32.5)
			(size 0.1 0.1)
			(layers "F.Paste")
			(options
				(clearance outline)
				(anchor circle)
			)
			(primitives
				(gr_arc
					(start 0 0)
					(mid 0.704278 1.28373)
					(end 0.608513 2.744826)
					(width 0.7)
				)
			)
		)
		(pad "1" thru_hole circle
			(at 0 0 90)
			(size 7.4 7.4)
			(drill 4.45)
			(layers "*.Cu" "*.Mask")
			(remove_unused_layers no)
			(net 1 "GND")
			(pintype "passive")
		)
	)
	(footprint "antmicro-footprints:R_0402_1005Metric"
		(layer "F.Cu")
		(at 195.1 127.3)
		(descr "Resistor SMD 0402")
		(tags "resistor SMD 0402")
		(property "Reference" "R81"
			(at -1.1 5.5 0)
			(layer "F.SilkS")
			(effects
				(font
					(size 0.7 0.7)
					(thickness 0.15)
				)
				(justify left bottom)
			)
		)
		(property "Value" "R_10k_0402"
			(at -1.011843 1.772047 0)
			(layer "F.Fab")
			(effects
				(font
					(size 0.7 0.7)
					(thickness 0.15)
				)
				(justify left bottom)
			)
		)
		(property "Datasheet" "https://www.bourns.com/docs/product-datasheets/cr.pdf"
			(at 0 0 0)
			(layer "F.Fab")
			(hide yes)
			(effects
				(font
					(size 1.27 1.27)
					(thickness 0.15)
				)
			)
		)
		(property "Description" "SMD Chip Resistor, 10 kohm, ± 1%, 62.5 mW, 0402 [1005 Metric], Thick Film, General Purpose"
			(at 0 0 0)
			(layer "F.Fab")
			(hide yes)
			(effects
				(font
					(size 1.27 1.27)
					(thickness 0.15)
				)
			)
		)
		(property "MPN" "CR0402-FX-1002GLF"
			(at 0 0 0)
			(unlocked yes)
			(layer "F.Fab")
			(hide yes)
			(effects
				(font
					(size 1 1)
					(thickness 0.15)
				)
			)
		)
		(property "Manufacturer" "Bourns"
			(at 0 0 0)
			(unlocked yes)
			(layer "F.Fab")
			(hide yes)
			(effects
				(font
					(size 1 1)
					(thickness 0.15)
				)
			)
		)
		(property "License" "Apache-2.0"
			(at 0 0 0)
			(unlocked yes)
			(layer "F.Fab")
			(hide yes)
			(effects
				(font
					(size 1 1)
					(thickness 0.15)
				)
			)
		)
		(property "Author" "Antmicro"
			(at 0 0 0)
			(unlocked yes)
			(layer "F.Fab")
			(hide yes)
			(effects
				(font
					(size 1 1)
					(thickness 0.15)
				)
			)
		)
		(property "Val" "10k"
			(at 0 0 0)
			(unlocked yes)
			(layer "F.Fab")
			(hide yes)
			(effects
				(font
					(size 1 1)
					(thickness 0.15)
				)
			)
		)
		(property "Tolerance" "1%"
			(at 0 0 0)
			(unlocked yes)
			(layer "F.Fab")
			(hide yes)
			(effects
				(font
					(size 1 1)
					(thickness 0.15)
				)
			)
		)
		(sheetname "/USB Hub/")
		(sheetfile "usb_hub.kicad_sch")
		(attr smd)
		(fp_rect
			(start -0.925 -0.47)
			(end 0.925 0.47)
			(stroke
				(width 0.05)
				(type default)
			)
			(fill no)
			(layer "F.CrtYd")
		)
		(fp_rect
			(start -0.5 -0.25)
			(end 0.5 0.25)
			(stroke
				(width 0.15)
				(type solid)
			)
			(fill no)
			(layer "F.Fab")
		)
		(fp_text user "${REFERENCE}"
			(at -0.95 3.168 0)
			(layer "F.Fab")
			(effects
				(font
					(size 0.7 0.7)
					(thickness 0.15)
				)
				(justify left bottom)
			)
		)
		(fp_text user "Author: Antmicro"
			(at -0.95 4.169 0)
			(layer "F.Fab")
			(effects
				(font
					(size 0.7 0.7)
					(thickness 0.15)
				)
				(justify left bottom)
			)
		)
		(fp_text user "License: Apache-2.0"
			(at -0.95 5.169 0)
			(layer "F.Fab")
			(effects
				(font
					(size 0.7 0.7)
					(thickness 0.15)
				)
				(justify left bottom)
			)
		)
		(pad "1" smd roundrect
			(at -0.48 0)
			(size 0.59 0.64)
			(layers "F.Cu" "F.Mask" "F.Paste")
			(roundrect_rratio 0.25)
			(net 2 "+3V3")
			(pintype "passive")
		)
		(pad "2" smd roundrect
			(at 0.48 0)
			(size 0.59 0.64)
			(layers "F.Cu" "F.Mask" "F.Paste")
			(roundrect_rratio 0.25)
			(net 916 "/USB Hub/TEST3")
			(pintype "passive")
		)
	)
)
